# T6G (Grand Teton) — schematic netlist excerpt (pin names and nets, part order shuffled) for the footprints in the layout excerpt that follows; sources: Cadence DE-HDL packaged netlist, KiCad conversion of 04192023_DAF0TMB3IC0_F0TG_MB_C_brd_V02_OCP.brd

C6552  Q_CAP_DIFFBUS  DIFF BUS_0.22UF 6.3V 20% X6S  pkg C0201  page 286 : \1\ = P5E_CPU0_P1_TX_BUF_C_DN<9> ; \2\ = P5E_CPU0_P1_TX_BUF_DN<9>
C292  Q_CAP  0.1UF 10V 10% X7S  pkg C0201  page 334 : A = P0V9_CPU1_RT_2D ; B = GND
C8012  Q_CAP  1UF 25V 10% EMPTY  pkg C0402  page 242 : A = FM_AC_PWR_BTN_R_N ; B = GND
C405  Q_CAP  100UF 4V 20% X6S  pkg C0805  page 345 : A = P0V9_CPU1_RT2_2A ; B = GND

(kicad_pcb
	(version 20260206)
	(generator "pcbnew")
	(generator_version "10.0")
	(general
		(thickness 1.6)
		(legacy_teardrops no)
	)
	(paper "A4")
	(title_block
		(title "04192023_DAF0TMB3IC0_F0TG_MB_C_brd_V02_OCP.brd")
		(comment 1 "Grand Teton / footprints 7033-7036 of 8354")
	)
	(layers
		(0 "F.Cu" signal "TOP")
		(4 "In1.Cu" signal "GND")
		(6 "In2.Cu" signal "IN1")
		(8 "In3.Cu" signal "GND1")
		(10 "In4.Cu" signal "IN2")
		(12 "In5.Cu" signal "GND2")
		(14 "In6.Cu" signal "IN3")
		(16 "In7.Cu" signal "GND3")
		(18 "In8.Cu" signal "VCC")
		(20 "In9.Cu" signal "VCC1")
		(22 "In10.Cu" signal "GND4")
		(24 "In11.Cu" signal "IN4")
		(26 "In12.Cu" signal "GND5")
		(28 "In13.Cu" signal "IN5")
		(30 "In14.Cu" signal "GND6")
		(32 "In15.Cu" signal "IN6")
		(34 "In16.Cu" signal "GND7")
		(2 "B.Cu" signal "BOTTOM")
		(9 "F.Adhes" user "F.Adhesive")
		(11 "B.Adhes" user "B.Adhesive")
		(13 "F.Paste" user "Package Geometry/Pastemask Top")
		(15 "B.Paste" user "Package Geometry/Pastemask Bottom")
		(5 "F.SilkS" user "Ref Des/Silkscreen Top")
		(7 "B.SilkS" user "Ref Des/Silkscreen Bottom")
		(1 "F.Mask" user "Board Geometry/Soldermask Top")
		(3 "B.Mask" user "Board Geometry/Soldermask Bottom")
		(17 "Dwgs.User" user "User.Drawings")
		(19 "Cmts.User" user "User.Comments")
		(21 "Eco1.User" user "User.Eco1")
		(23 "Eco2.User" user "User.Eco2")
		(25 "Edge.Cuts" user "Board Geometry/Outline")
		(27 "Margin" user)
		(31 "F.CrtYd" user "Package Geometry/Place Bound Top")
		(29 "B.CrtYd" user "Package Geometry/Place Bound Bottom")
		(35 "F.Fab" user "Ref Des/Assembly Top")
		(33 "B.Fab" user "Ref Des/Assembly Bottom")
	)
	(footprint ""
		(layer "B.Cu")
		(at 199.39 -144.272 90)
		(property "Reference" "C8012"
			(at 0 0 90)
			(layer "B.SilkS")
			(hide yes)
			(effects
				(font
					(size 1.27 1.27)
				)
				(justify mirror)
			)
		)
		(property "Value" ""
			(at 0 0 90)
			(layer "B.Fab")
			(effects
				(font
					(size 1.27 1.27)
				)
				(justify mirror)
			)
		)
		(duplicate_pad_numbers_are_jumpers no)
		(fp_line
			(start 0.7874 -0.4064)
			(end -0.7874 -0.4064)
			(stroke
				(width 0.1524)
				(type default)
			)
			(layer "B.SilkS")
		)
		(fp_line
			(start -0.7874 -0.4064)
			(end -0.7874 0.4064)
			(stroke
				(width 0.1524)
				(type default)
			)
			(layer "B.SilkS")
		)
		(fp_line
			(start 0.7874 0.4064)
			(end 0.7874 -0.4064)
			(stroke
				(width 0.1524)
				(type default)
			)
			(layer "B.SilkS")
		)
		(fp_line
			(start -0.7874 0.4064)
			(end 0.7874 0.4064)
			(stroke
				(width 0.1524)
				(type default)
			)
			(layer "B.SilkS")
		)
		(fp_line
			(start 0.67945 -0.305054)
			(end 0.12065 -0.305054)
			(stroke
				(width 0.1)
				(type default)
			)
			(layer "B.Fab")
		)
		(fp_line
			(start 0.12065 -0.305054)
			(end 0.12065 -0.2794)
			(stroke
				(width 0.1)
				(type default)
			)
			(layer "B.Fab")
		)
		(fp_line
			(start -0.12065 -0.3048)
			(end -0.67945 -0.3048)
			(stroke
				(width 0.1)
				(type default)
			)
			(layer "B.Fab")
		)
		(fp_line
			(start -0.67945 -0.3048)
			(end -0.67945 0.3048)
			(stroke
				(width 0.1)
				(type default)
			)
			(layer "B.Fab")
		)
		(fp_line
			(start 0.12065 -0.2794)
			(end -0.12065 -0.2794)
			(stroke
				(width 0.1)
				(type default)
			)
			(layer "B.Fab")
		)
		(fp_line
			(start -0.12065 -0.2794)
			(end -0.12065 -0.3048)
			(stroke
				(width 0.1)
				(type default)
			)
			(layer "B.Fab")
		)
		(fp_line
			(start 0.12065 0.2794)
			(end 0.12065 0.3048)
			(stroke
				(width 0.1)
				(type default)
			)
			(layer "B.Fab")
		)
		(fp_line
			(start -0.120396 0.2794)
			(end 0.12065 0.2794)
			(stroke
				(width 0.1)
				(type default)
			)
			(layer "B.Fab")
		)
		(fp_line
			(start 0.67945 0.3048)
			(end 0.67945 -0.305054)
			(stroke
				(width 0.1)
				(type default)
			)
			(layer "B.Fab")
		)
		(fp_line
			(start 0.12065 0.3048)
			(end 0.67945 0.3048)
			(stroke
				(width 0.1)
				(type default)
			)
			(layer "B.Fab")
		)
		(fp_line
			(start -0.120396 0.3048)
			(end -0.120396 0.2794)
			(stroke
				(width 0.1)
				(type default)
			)
			(layer "B.Fab")
		)
		(fp_line
			(start -0.67945 0.3048)
			(end -0.120396 0.3048)
			(stroke
				(width 0.1)
				(type default)
			)
			(layer "B.Fab")
		)
		(pad "1" smd circle
			(at 0.40005 0 270)
			(size 0 0)
			(layers "B.Cu" "B.Mask" "B.Paste")
			(net "FM_AC_PWR_BTN_R_N")
		)
		(pad "2" smd circle
			(at -0.40005 0 270)
			(size 0 0)
			(layers "B.Cu" "B.Mask" "B.Paste")
			(net "GND")
		)
	)
	(footprint ""
		(layer "B.Cu")
		(at 142.047214 -390.587484)
		(property "Reference" "C405"
			(at 0 0 0)
			(layer "B.SilkS")
			(hide yes)
			(effects
				(font
					(size 1.27 1.27)
				)
				(justify mirror)
			)
		)
		(property "Value" ""
			(at 0 0 0)
			(layer "B.Fab")
			(effects
				(font
					(size 1.27 1.27)
				)
				(justify mirror)
			)
		)
		(duplicate_pad_numbers_are_jumpers no)
		(fp_line
			(start -1.524 -0.762)
			(end -1.524 0.762)
			(stroke
				(width 0.1524)
				(type default)
			)
			(layer "B.SilkS")
		)
		(fp_line
			(start -1.524 0.762)
			(end 1.524 0.762)
			(stroke
				(width 0.1524)
				(type default)
			)
			(layer "B.SilkS")
		)
		(fp_line
			(start 1.524 -0.762)
			(end -1.524 -0.762)
			(stroke
				(width 0.1524)
				(type default)
			)
			(layer "B.SilkS")
		)
		(fp_line
			(start 1.524 0.762)
			(end 1.524 -0.762)
			(stroke
				(width 0.1524)
				(type default)
			)
			(layer "B.SilkS")
		)
		(fp_line
			(start -1.1049 -0.724916)
			(end 1.1049 -0.724916)
			(stroke
				(width 0.1)
				(type default)
			)
			(layer "B.Fab")
		)
		(fp_line
			(start -1.1049 0.724916)
			(end -1.1049 -0.724916)
			(stroke
				(width 0.1)
				(type default)
			)
			(layer "B.Fab")
		)
		(fp_line
			(start 1.1049 -0.724916)
			(end 1.1049 0.724916)
			(stroke
				(width 0.1)
				(type default)
			)
			(layer "B.Fab")
		)
		(fp_line
			(start 1.1049 0.724916)
			(end -1.1049 0.724916)
			(stroke
				(width 0.1)
				(type default)
			)
			(layer "B.Fab")
		)
		(pad "1" smd rect
			(at 0.889 0)
			(size 1.016 1.27)
			(layers "B.Cu" "B.Mask" "B.Paste")
			(net "P0V9_CPU1_RT2_2A")
		)
		(pad "2" smd rect
			(at -0.889 0)
			(size 1.016 1.27)
			(layers "B.Cu" "B.Mask" "B.Paste")
			(net "GND")
		)
	)
	(footprint ""
		(layer "B.Cu")
		(at 85.906356 -386.766562 90)
		(property "Reference" "C292"
			(at 0 0 90)
			(layer "B.SilkS")
			(hide yes)
			(effects
				(font
					(size 1.27 1.27)
				)
				(justify mirror)
			)
		)
		(property "Value" ""
			(at 0 0 90)
			(layer "B.Fab")
			(effects
				(font
					(size 1.27 1.27)
				)
				(justify mirror)
			)
		)
		(duplicate_pad_numbers_are_jumpers no)
		(fp_line
			(start 0.299974 -0.150114)
			(end -0.299974 -0.150114)
			(stroke
				(width 0.1)
				(type default)
			)
			(layer "B.Fab")
		)
		(fp_line
			(start -0.299974 -0.150114)
			(end -0.299974 0.150114)
			(stroke
				(width 0.1)
				(type default)
			)
			(layer "B.Fab")
		)
		(fp_line
			(start 0.299974 0.150114)
			(end 0.299974 -0.150114)
			(stroke
				(width 0.1)
				(type default)
			)
			(layer "B.Fab")
		)
		(fp_line
			(start -0.299974 0.150114)
			(end 0.299974 0.150114)
			(stroke
				(width 0.1)
				(type default)
			)
			(layer "B.Fab")
		)
		(pad "1" smd rect
			(at 0.2667 0 270)
			(size 0.3048 0.381)
			(layers "B.Cu" "B.Mask" "B.Paste")
			(net "P0V9_CPU1_RT_2D")
		)
		(pad "2" smd rect
			(at -0.2667 0 270)
			(size 0.3048 0.381)
			(layers "B.Cu" "B.Mask" "B.Paste")
			(net "GND")
		)
	)
	(footprint ""
		(layer "B.Cu")
		(at 332.869286 -416.899344 90)
		(property "Reference" "C6552"
			(at 0 0 90)
			(layer "B.SilkS")
			(hide yes)
			(effects
				(font
					(size 1.27 1.27)
				)
				(justify mirror)
			)
		)
		(property "Value" ""
			(at 0 0 90)
			(layer "B.Fab")
			(effects
				(font
					(size 1.27 1.27)
				)
				(justify mirror)
			)
		)
		(duplicate_pad_numbers_are_jumpers no)
		(fp_line
			(start 0.299974 -0.150114)
			(end -0.299974 -0.150114)
			(stroke
				(width 0.1)
				(type default)
			)
			(layer "B.Fab")
		)
		(fp_line
			(start -0.299974 -0.150114)
			(end -0.299974 0.150114)
			(stroke
				(width 0.1)
				(type default)
			)
			(layer "B.Fab")
		)
		(fp_line
			(start 0.299974 0.150114)
			(end 0.299974 -0.150114)
			(stroke
				(width 0.1)
				(type default)
			)
			(layer "B.Fab")
		)
		(fp_line
			(start -0.299974 0.150114)
			(end 0.299974 0.150114)
			(stroke
				(width 0.1)
				(type default)
			)
			(layer "B.Fab")
		)
		(pad "1" smd rect
			(at 0.2667 0 270)
			(size 0.3048 0.381)
			(layers "B.Cu" "B.Mask" "B.Paste")
			(net "P5E_CPU0_P1_TX_BUF_C_DN<9>")
		)
		(pad "2" smd rect
			(at -0.2667 0 270)
			(size 0.3048 0.381)
			(layers "B.Cu" "B.Mask" "B.Paste")
			(net "P5E_CPU0_P1_TX_BUF_DN<9>")
		)
	)
)
